# S9S_MB_2U (Grand Teton) — schematic netlist excerpt (pin names and nets, part order shuffled) for the footprints in the layout excerpt that follows; sources: Cadence DE-HDL packaged netlist, KiCad conversion of 03242023_DA0F0TMBIJ0_F0T_Motherboard_J_brd_V01_OCP.brd

J24  SCONN288_ADR50017P087CC  SCONN288_ADR50017-P087CC IO  pkg DDR288S_1-1VXB  page 105
  VIN_BULK0  = P12V_S3_AUX_CPU1_NVDIMM
  RFU0  = TP_CHD_CPU1_DIMM2_FRU_0
  VIN_MGMT  = P3V3_AUX
  HSCL  = I3C_SPD_DDRABCD_CPU1_LVC1_SCL_7
  HSDA  = I3C_SPD_DDRABCD_CPU1_LVC1_SDA
  VSS0  = GND
  DQ0_A  = M_D_CPU1_SA_DQ<0>
  VSS1  = GND
  DQ1_A  = M_D_CPU1_SA_DQ<1>
  VSS2  = GND
  DQS0_A_T  = M_D_CPU1_SA_DQS_DP<0>
  DQS0_A_C  = M_D_CPU1_SA_DQS_DN<0>
  VSS3  = GND
  DQ4_A  = M_D_CPU1_SA_DQ<4>
  VSS4  = GND
  DQ5_A  = M_D_CPU1_SA_DQ<5>
  VSS5  = GND
  DQ8_A  = M_D_CPU1_SA_DQ<8>
  VSS6  = GND
  DQ9_A  = M_D_CPU1_SA_DQ<9>
  VSS7  = GND
  DQS1_A_T  = M_D_CPU1_SA_DQS_DP<1>
  DQS1_A_C  = M_D_CPU1_SA_DQS_DN<1>
  VSS8  = GND
  DQ12_A  = M_D_CPU1_SA_DQ<12>
  VSS9  = GND
  DQ13_A  = M_D_CPU1_SA_DQ<13>
  VSS10  = GND
  DQ16_A  = M_D_CPU1_SA_DQ<16>
  VSS11  = GND
  DQ17_A  = M_D_CPU1_SA_DQ<17>
  VSS12  = GND
  DQS2_A_T  = M_D_CPU1_SA_DQS_DP<2>
  DQS2_A_C  = M_D_CPU1_SA_DQS_DN<2>
  VSS13  = GND
  DQ20_A  = M_D_CPU1_SA_DQ<20>
  VSS14  = GND
  DQ21_A  = M_D_CPU1_SA_DQ<21>
  VSS15  = GND
  DQ24_A  = M_D_CPU1_SA_DQ<24>
  VSS16  = GND
  DQ25_A  = M_D_CPU1_SA_DQ<25>
  VSS17  = GND
  DQS3_A_T  = M_D_CPU1_SA_DQS_DP<3>
  DQS3_A_C  = M_D_CPU1_SA_DQS_DN<3>
  VSS18  = GND
  DQ28_A  = M_D_CPU1_SA_DQ<28>
  VSS19  = GND
  DQ29_A  = M_D_CPU1_SA_DQ<29>
  VSS20  = GND
  CB0_A  = M_D_CPU1_SA_CB<0>
  VSS21  = GND
  CB1_A  = M_D_CPU1_SA_CB<1>
  VSS22  = GND
  DQS4_A_T  = M_D_CPU1_SA_DQS_DP<4>
  DQS4_A_C  = M_D_CPU1_SA_DQS_DN<4>
  VSS23  = GND
  CB4_A  = M_D_CPU1_SA_CB<4>
  VSS24  = GND
  CB5_A  = M_D_CPU1_SA_CB<5>
  VSS25  = GND
  ALERT_N  = M_D_CPU1_ALERT_N
  VSS26  = GND
  CS0_A_N  = M_D_CPU1_SA_CS_N<2>
  VSS27  = GND
  CA0_A  = M_D_CPU1_SA_CA<0>
  VSS28  = GND
  CA2_A  = M_D_CPU1_SA_CA<2>
  VSS29  = GND
  CA4_A  = M_D_CPU1_SA_CA<4>
  VSS30  = GND
  CA6_A  = M_D_CPU1_SA_CA<6>
  VSS31  = GND
  PAR_A  = M_D_CPU1_SA_PAR
  VSS32  = GND
  CA0_B  = M_D_CPU1_SB_CA<0>
  VSS33  = GND
  CA2_B  = M_D_CPU1_SB_CA<2>
  VSS34  = GND
  CA4_B  = M_D_CPU1_SB_CA<4>
  VSS35  = GND
  CA6_B  = M_D_CPU1_SB_CA<6>
  VSS36  = GND
  CS0_B_N  = M_D_CPU1_SB_CS_N<2>
  VSS37  = GND
  \lbd||rsp_a_n\  = M_D_CPU1_SA_RSP<1>
  \lbs||rsp_b_n\  = M_D_CPU1_SB_RSP<1>
  VSS38  = GND
  CB4_B  = M_D_CPU1_SB_CB<4>
  VSS39  = GND
  CB5_B  = M_D_CPU1_SB_CB<5>
  VSS40  = GND
  \dqs9_b_t||tdqs9_b_t||dbi4_b_n\  = M_D_CPU1_SB_DQS_DP<9>
  \dqs9_b_c||tdqs9_b_c\  = M_D_CPU1_SB_DQS_DN<9>
  VSS41  = GND
  CB0_B  = M_D_CPU1_SB_CB<0>
  VSS42  = GND
  CB1_B  = M_D_CPU1_SB_CB<1>
  VSS43  = GND
  DQ0_B  = M_D_CPU1_SB_DQ<0>
  VSS44  = GND
  DQ1_B  = M_D_CPU1_SB_DQ<1>
  VSS45  = GND
  DQS0_B_T  = M_D_CPU1_SB_DQS_DP<0>
  DQS0_B_C  = M_D_CPU1_SB_DQS_DN<0>
  VSS46  = GND
  DQ4_B  = M_D_CPU1_SB_DQ<4>
  VSS47  = GND
  DQ5_B  = M_D_CPU1_SB_DQ<5>
  VSS48  = GND
  DQ8_B  = M_D_CPU1_SB_DQ<8>
  VSS49  = GND
  DQ9_B  = M_D_CPU1_SB_DQ<9>
  VSS50  = GND
  DQS1_B_T  = M_D_CPU1_SB_DQS_DP<1>
  DQS1_B_C  = M_D_CPU1_SB_DQS_DN<1>
  VSS51  = GND
  DQ12_B  = M_D_CPU1_SB_DQ<12>
  VSS52  = GND
  DQ13_B  = M_D_CPU1_SB_DQ<13>
  VSS53  = GND
  DQ16_B  = M_D_CPU1_SB_DQ<16>
  VSS54  = GND
  DQ17_B  = M_D_CPU1_SB_DQ<17>
  VSS55  = GND
  DQS2_B_T  = M_D_CPU1_SB_DQS_DP<2>
  DQS2_B_C  = M_D_CPU1_SB_DQS_DN<2>
  VSS56  = GND
  DQ20_B  = M_D_CPU1_SB_DQ<20>
  VSS57  = GND
  DQ21_B  = M_D_CPU1_SB_DQ<21>
  VSS58  = GND
  DQ24_B  = M_D_CPU1_SB_DQ<24>
  VSS59  = GND
  DQ25_B  = M_D_CPU1_SB_DQ<25>
  VSS60  = GND
  DQS3_B_T  = M_D_CPU1_SB_DQS_DP<3>
  DQS3_B_C  = M_D_CPU1_SB_DQS_DN<3>
  VSS61  = GND
  DQ28_B  = M_D_CPU1_SB_DQ<28>
  VSS62  = GND
  DQ29_B  = M_D_CPU1_SB_DQ<29>
  VSS63  = GND
  RFU1  = TP_CHD_CPU1_DIMM2_FRU_1
  VIN_BULK1  = P12V_S3_AUX_CPU1_NVDIMM
  VIN_BULK2  = P12V_S3_AUX_CPU1_NVDIMM
  \pwr_good||fail_n\  = PWRGD_CHD_CPU1_DIMM2
  HSA  = PD_CHD_CPU1_DIMM2_SAA
  RFU2  = TP_CHD_CPU1_DIMM2_FRU_2
  RFU3  = TP_CHD_CPU1_DIMM2_FRU_3
  VSS64  = GND
  DQ2_A  = M_D_CPU1_SA_DQ<2>
  VSS65  = GND
  DQ3_A  = M_D_CPU1_SA_DQ<3>
  VSS66  = GND
  \dqs5_a_c||tdqs5_a_c||dqs5_a_t||tdqs5_a_t\  = M_D_CPU1_SA_DQS_DN<5>
  \dqs5_a_t||tdqs5_a_t\  = M_D_CPU1_SA_DQS_DP<5>
  VSS67  = GND
  DQ6_A  = M_D_CPU1_SA_DQ<6>
  VSS68  = GND
  DQ7_A  = M_D_CPU1_SA_DQ<7>
  VSS69  = GND
  DQ10_A  = M_D_CPU1_SA_DQ<10>
  VSS70  = GND
  DQ11_A  = M_D_CPU1_SA_DQ<11>
  VSS71  = GND
  \dqs6_a_c||tdqs6_a_c||dqs6_a_t||tdqs6_a_t\  = M_D_CPU1_SA_DQS_DN<6>
  \dqs6_a_t||tdqs6_a_t\  = M_D_CPU1_SA_DQS_DP<6>
  VSS72  = GND
  DQ14_A  = M_D_CPU1_SA_DQ<14>
  VSS73  = GND
  DQ15_A  = M_D_CPU1_SA_DQ<15>
  VSS74  = GND
  DQ18_A  = M_D_CPU1_SA_DQ<18>
  VSS75  = GND
  DQ19_A  = M_D_CPU1_SA_DQ<19>
  VSS76  = GND
  \dqs7_a_c||tdqs7_a_c\  = M_D_CPU1_SA_DQS_DN<7>
  \dqs7_a_t||tdqs7_a_t\  = M_D_CPU1_SA_DQS_DP<7>
  VSS77  = GND
  DQ22_A  = M_D_CPU1_SA_DQ<22>
  VSS78  = GND
  DQ23_A  = M_D_CPU1_SA_DQ<23>
  VSS79  = GND
  DQ26_A  = M_D_CPU1_SA_DQ<26>
  VSS80  = GND
  DQ27_A  = M_D_CPU1_SA_DQ<27>
  VSS81  = GND
  \dqs8_a_c||tdqs8_a_c\  = M_D_CPU1_SA_DQS_DN<8>
  \dqs8_a_t||tdqs8_a_t\  = M_D_CPU1_SA_DQS_DP<8>
  VSS82  = GND
  DQ30_A  = M_D_CPU1_SA_DQ<30>
  VSS83  = GND
  DQ31_A  = M_D_CPU1_SA_DQ<31>
  VSS84  = GND
  CB2_A  = M_D_CPU1_SA_CB<2>
  VSS85  = GND
  CB3_A  = M_D_CPU1_SA_CB<3>
  VSS86  = GND
  \dqs9_a_c||tdqs9_a_c\  = M_D_CPU1_SA_DQS_DN<9>
  \dqs9_a_t||tdqs9_a_t\  = M_D_CPU1_SA_DQS_DP<9>
  VSS87  = GND
  CB6_A  = M_D_CPU1_SA_CB<6>
  VSS88  = GND
  CB7_A  = M_D_CPU1_SA_CB<7>
  VSS89  = GND
  RESET_N  = RST_M_CD_CPU1_FPGA_N
  VSS90  = GND
  CS1_A_N  = M_D_CPU1_SA_CS_N<3>
  VSS91  = GND
  CA1_A  = M_D_CPU1_SA_CA<1>
  VSS92  = GND
  CA3_A  = M_D_CPU1_SA_CA<3>
  VSS93  = GND
  CA5_A  = M_D_CPU1_SA_CA<5>
  VSS94  = GND
  CK_T  = M_D_CPU1_CLK_DP<1>
  CK_C  = M_D_CPU1_CLK_DN<1>
  VSS95  = GND
  RFU4  = TP_CHD_CPU1_DIMM2_FRU_4
  CA1_B  = M_D_CPU1_SB_CA<1>
  VSS96  = GND
  CA3_B  = M_D_CPU1_SB_CA<3>
  VSS97  = GND
  CA5_B  = M_D_CPU1_SB_CA<5>
  VSS98  = GND
  PAR_B  = M_D_CPU1_SB_PAR
  VSS99  = GND
  CS1_B_N  = M_D_CPU1_SB_CS_N<3>
  VSS100  = GND
  RFU5  = TP_CHD_CPU1_DIMM2_FRU_5
  RFU6  = TP_CHD_CPU1_DIMM2_FRU_6
  VSS101  = GND
  CB6_B  = M_D_CPU1_SB_CB<6>
  VSS102  = GND
  CB7_B  = M_D_CPU1_SB_CB<7>
  VSS103  = GND
  DQS4_B_C  = M_D_CPU1_SB_DQS_DN<4>
  DQS4_B_T  = M_D_CPU1_SB_DQS_DP<4>
  VSS104  = GND
  CB2_B  = M_D_CPU1_SB_CB<2>
  VSS105  = GND
  CB3_B  = M_D_CPU1_SB_CB<3>
  VSS106  = GND
  DQ2_B  = M_D_CPU1_SB_DQ<2>
  VSS107  = GND
  DQ3_B  = M_D_CPU1_SB_DQ<3>
  VSS108  = GND
  \dqs5_b_c||tdqs5_b_c\  = M_D_CPU1_SB_DQS_DN<5>
  \dqs5_b_t||tdqs5_b_t\  = M_D_CPU1_SB_DQS_DP<5>
  VSS109  = GND
  DQ6_B  = M_D_CPU1_SB_DQ<6>
  VSS110  = GND
  DQ7_B  = M_D_CPU1_SB_DQ<7>
  VSS111  = GND
  DQ10_B  = M_D_CPU1_SB_DQ<10>
  VSS112  = GND
  DQ11_B  = M_D_CPU1_SB_DQ<11>
  VSS113  = GND
  \dqs6_b_c||tdqs6_b_c\  = M_D_CPU1_SB_DQS_DN<6>
  \dqs6_b_t||tdqs6_b_t\  = M_D_CPU1_SB_DQS_DP<6>
  VSS114  = GND
  DQ14_B  = M_D_CPU1_SB_DQ<14>
  VSS115  = GND
  DQ15_B  = M_D_CPU1_SB_DQ<15>
  VSS116  = GND
  DQ18_B  = M_D_CPU1_SB_DQ<18>
  VSS117  = GND
  DQ19_B  = M_D_CPU1_SB_DQ<19>
  VSS118  = GND
  \dqs7_b_c||tdqs7_b_c\  = M_D_CPU1_SB_DQS_DN<7>
  \dqs7_b_t||tdqs7_b_t\  = M_D_CPU1_SB_DQS_DP<7>
  VSS119  = GND
  DQ22_B  = M_D_CPU1_SB_DQ<22>
  VSS120  = GND
  DQ23_B  = M_D_CPU1_SB_DQ<23>
  VSS121  = GND
  DQ26_B  = M_D_CPU1_SB_DQ<26>
  VSS122  = GND
  DQ27_B  = M_D_CPU1_SB_DQ<27>
  VSS123  = GND
  \dqs8_b_c||tdqs8_b_c\  = M_D_CPU1_SB_DQS_DN<8>
  \dqs8_b_t||tdqs8_b_t\  = M_D_CPU1_SB_DQS_DP<8>
  VSS124  = GND
  DQ30_B  = M_D_CPU1_SB_DQ<30>
  VSS125  = GND
  DQ31_B  = M_D_CPU1_SB_DQ<31>
  VSS126  = GND
  G1  = GND
  G2  = GND
  G3  = GND

(kicad_pcb
	(version 20260206)
	(generator "pcbnew")
	(generator_version "10.0")
	(general
		(thickness 1.6)
		(legacy_teardrops no)
	)
	(paper "A4")
	(title_block
		(title "03242023_DA0F0TMBIJ0_F0T_Motherboard_J_brd_V01_OCP.brd")
		(comment 1 "Grand Teton / footprint 1660 of 6105 (J24), pads 1-45 of 291")
	)
	(layers
		(0 "F.Cu" signal "TOP")
		(4 "In1.Cu" signal "GND")
		(6 "In2.Cu" signal "IN1")
		(8 "In3.Cu" signal "GND1")
		(10 "In4.Cu" signal "IN2")
		(12 "In5.Cu" signal "GND2")
		(14 "In6.Cu" signal "IN3")
		(16 "In7.Cu" signal "GND3")
		(18 "In8.Cu" signal "VCC")
		(20 "In9.Cu" signal "VCC1")
		(22 "In10.Cu" signal "GND4")
		(24 "In11.Cu" signal "IN4")
		(26 "In12.Cu" signal "GND5")
		(28 "In13.Cu" signal "IN5")
		(30 "In14.Cu" signal "GND6")
		(32 "In15.Cu" signal "IN6")
		(34 "In16.Cu" signal "GND7")
		(2 "B.Cu" signal "BOTTOM")
		(9 "F.Adhes" user "F.Adhesive")
		(11 "B.Adhes" user "B.Adhesive")
		(13 "F.Paste" user "Package Geometry/Pastemask Top")
		(15 "B.Paste" user "Package Geometry/Pastemask Bottom")
		(5 "F.SilkS" user "Ref Des/Silkscreen Top")
		(7 "B.SilkS" user "Ref Des/Silkscreen Bottom")
		(1 "F.Mask" user "Board Geometry/Soldermask Top")
		(3 "B.Mask" user "Board Geometry/Soldermask Bottom")
		(17 "Dwgs.User" user "User.Drawings")
		(19 "Cmts.User" user "User.Comments")
		(21 "Eco1.User" user "User.Eco1")
		(23 "Eco2.User" user "User.Eco2")
		(25 "Edge.Cuts" user "Board Geometry/Outline")
		(27 "Margin" user)
		(31 "F.CrtYd" user "Package Geometry/Place Bound Top")
		(29 "B.CrtYd" user "Package Geometry/Place Bound Bottom")
		(35 "F.Fab" user "Ref Des/Assembly Top")
		(33 "B.Fab" user "Ref Des/Assembly Bottom")
	)
	(footprint ""
		(layer "F.Cu")
		(at 17.73428 -258.091686)
		(property "Reference" "J24"
			(at -3.0607 -81.901792 0)
			(unlocked yes)
			(layer "F.SilkS")
			(effects
				(font
					(size 0.7874 0.5842)
					(thickness 0.1524)
				)
				(justify left)
			)
		)
		(property "Value" ""
			(at 0 0 0)
			(layer "F.Fab")
			(effects
				(font
					(size 1.27 1.27)
				)
			)
		)
		(duplicate_pad_numbers_are_jumpers no)
		(pad "1" smd rect
			(at -2.050034 -63.324994 270)
			(size 0.519938 1.4986)
			(layers "F.Cu" "F.Mask" "F.Paste")
			(net "P12V_S3_AUX_CPU1_NVDIMM")
		)
		(pad "2" smd rect
			(at -2.050034 -62.47511 270)
			(size 0.519938 1.4986)
			(layers "F.Cu" "F.Mask" "F.Paste")
			(net "TP_CHD_CPU1_DIMM2_FRU_0")
		)
		(pad "3" smd rect
			(at -2.050034 -61.624972 270)
			(size 0.519938 1.4986)
			(layers "F.Cu" "F.Mask" "F.Paste")
			(net "P3V3_AUX")
		)
		(pad "4" smd rect
			(at -2.050034 -60.775088 270)
			(size 0.519938 1.4986)
			(layers "F.Cu" "F.Mask" "F.Paste")
			(net "I3C_SPD_DDRABCD_CPU1_LVC1_SCL_7")
		)
		(pad "5" smd rect
			(at -2.050034 -59.92495 270)
			(size 0.519938 1.4986)
			(layers "F.Cu" "F.Mask" "F.Paste")
			(net "I3C_SPD_DDRABCD_CPU1_LVC1_SDA")
		)
		(pad "6" smd rect
			(at -2.050034 -59.075066 270)
			(size 0.519938 1.4986)
			(layers "F.Cu" "F.Mask" "F.Paste")
			(net "GND")
		)
		(pad "7" smd rect
			(at -2.050034 -58.224928 270)
			(size 0.519938 1.4986)
			(layers "F.Cu" "F.Mask" "F.Paste")
			(net "M_D_CPU1_SA_DQ<0>")
		)
		(pad "8" smd rect
			(at -2.050034 -57.375044 270)
			(size 0.519938 1.4986)
			(layers "F.Cu" "F.Mask" "F.Paste")
			(net "GND")
		)
		(pad "9" smd rect
			(at -2.050034 -56.524906 270)
			(size 0.519938 1.4986)
			(layers "F.Cu" "F.Mask" "F.Paste")
			(net "M_D_CPU1_SA_DQ<1>")
		)
		(pad "10" smd rect
			(at -2.050034 -55.675022 270)
			(size 0.519938 1.4986)
			(layers "F.Cu" "F.Mask" "F.Paste")
			(net "GND")
		)
		(pad "11" smd rect
			(at -2.050034 -54.824884 270)
			(size 0.519938 1.4986)
			(layers "F.Cu" "F.Mask" "F.Paste")
			(net "M_D_CPU1_SA_DQS_DP<0>")
		)
		(pad "12" smd rect
			(at -2.050034 -53.975 270)
			(size 0.519938 1.4986)
			(layers "F.Cu" "F.Mask" "F.Paste")
			(net "M_D_CPU1_SA_DQS_DN<0>")
		)
		(pad "13" smd rect
			(at -2.050034 -53.125116 270)
			(size 0.519938 1.4986)
			(layers "F.Cu" "F.Mask" "F.Paste")
			(net "GND")
		)
		(pad "14" smd rect
			(at -2.050034 -52.274978 270)
			(size 0.519938 1.4986)
			(layers "F.Cu" "F.Mask" "F.Paste")
			(net "M_D_CPU1_SA_DQ<4>")
		)
		(pad "15" smd rect
			(at -2.050034 -51.425094 270)
			(size 0.519938 1.4986)
			(layers "F.Cu" "F.Mask" "F.Paste")
			(net "GND")
		)
		(pad "16" smd rect
			(at -2.050034 -50.574956 270)
			(size 0.519938 1.4986)
			(layers "F.Cu" "F.Mask" "F.Paste")
			(net "M_D_CPU1_SA_DQ<5>")
		)
		(pad "17" smd rect
			(at -2.050034 -49.725072 270)
			(size 0.519938 1.4986)
			(layers "F.Cu" "F.Mask" "F.Paste")
			(net "GND")
		)
		(pad "18" smd rect
			(at -2.050034 -48.874934 270)
			(size 0.519938 1.4986)
			(layers "F.Cu" "F.Mask" "F.Paste")
			(net "M_D_CPU1_SA_DQ<8>")
		)
		(pad "19" smd rect
			(at -2.050034 -48.02505 270)
			(size 0.519938 1.4986)
			(layers "F.Cu" "F.Mask" "F.Paste")
			(net "GND")
		)
		(pad "20" smd rect
			(at -2.050034 -47.174912 270)
			(size 0.519938 1.4986)
			(layers "F.Cu" "F.Mask" "F.Paste")
			(net "M_D_CPU1_SA_DQ<9>")
		)
		(pad "21" smd rect
			(at -2.050034 -46.325028 270)
			(size 0.519938 1.4986)
			(layers "F.Cu" "F.Mask" "F.Paste")
			(net "GND")
		)
		(pad "22" smd rect
			(at -2.050034 -45.47489 270)
			(size 0.519938 1.4986)
			(layers "F.Cu" "F.Mask" "F.Paste")
			(net "M_D_CPU1_SA_DQS_DP<1>")
		)
		(pad "23" smd rect
			(at -2.050034 -44.625006 270)
			(size 0.519938 1.4986)
			(layers "F.Cu" "F.Mask" "F.Paste")
			(net "M_D_CPU1_SA_DQS_DN<1>")
		)
		(pad "24" smd rect
			(at -2.050034 -43.775122 270)
			(size 0.519938 1.4986)
			(layers "F.Cu" "F.Mask" "F.Paste")
			(net "GND")
		)
		(pad "25" smd rect
			(at -2.050034 -42.924984 270)
			(size 0.519938 1.4986)
			(layers "F.Cu" "F.Mask" "F.Paste")
			(net "M_D_CPU1_SA_DQ<12>")
		)
		(pad "26" smd rect
			(at -2.050034 -42.0751 270)
			(size 0.519938 1.4986)
			(layers "F.Cu" "F.Mask" "F.Paste")
			(net "GND")
		)
		(pad "27" smd rect
			(at -2.050034 -41.224962 270)
			(size 0.519938 1.4986)
			(layers "F.Cu" "F.Mask" "F.Paste")
			(net "M_D_CPU1_SA_DQ<13>")
		)
		(pad "28" smd rect
			(at -2.050034 -40.375078 270)
			(size 0.519938 1.4986)
			(layers "F.Cu" "F.Mask" "F.Paste")
			(net "GND")
		)
		(pad "29" smd rect
			(at -2.050034 -39.52494 270)
			(size 0.519938 1.4986)
			(layers "F.Cu" "F.Mask" "F.Paste")
			(net "M_D_CPU1_SA_DQ<16>")
		)
		(pad "30" smd rect
			(at -2.050034 -38.675056 270)
			(size 0.519938 1.4986)
			(layers "F.Cu" "F.Mask" "F.Paste")
			(net "GND")
		)
		(pad "31" smd rect
			(at -2.050034 -37.824918 270)
			(size 0.519938 1.4986)
			(layers "F.Cu" "F.Mask" "F.Paste")
			(net "M_D_CPU1_SA_DQ<17>")
		)
		(pad "32" smd rect
			(at -2.050034 -36.975034 270)
			(size 0.519938 1.4986)
			(layers "F.Cu" "F.Mask" "F.Paste")
			(net "GND")
		)
		(pad "33" smd rect
			(at -2.050034 -36.124896 270)
			(size 0.519938 1.4986)
			(layers "F.Cu" "F.Mask" "F.Paste")
			(net "M_D_CPU1_SA_DQS_DP<2>")
		)
		(pad "34" smd rect
			(at -2.050034 -35.275012 270)
			(size 0.519938 1.4986)
			(layers "F.Cu" "F.Mask" "F.Paste")
			(net "M_D_CPU1_SA_DQS_DN<2>")
		)
		(pad "35" smd rect
			(at -2.050034 -34.425128 270)
			(size 0.519938 1.4986)
			(layers "F.Cu" "F.Mask" "F.Paste")
			(net "GND")
		)
		(pad "36" smd rect
			(at -2.050034 -33.57499 270)
			(size 0.519938 1.4986)
			(layers "F.Cu" "F.Mask" "F.Paste")
			(net "M_D_CPU1_SA_DQ<20>")
		)
		(pad "37" smd rect
			(at -2.050034 -32.725106 270)
			(size 0.519938 1.4986)
			(layers "F.Cu" "F.Mask" "F.Paste")
			(net "GND")
		)
		(pad "38" smd rect
			(at -2.050034 -31.874968 270)
			(size 0.519938 1.4986)
			(layers "F.Cu" "F.Mask" "F.Paste")
			(net "M_D_CPU1_SA_DQ<21>")
		)
		(pad "39" smd rect
			(at -2.050034 -31.025084 270)
			(size 0.519938 1.4986)
			(layers "F.Cu" "F.Mask" "F.Paste")
			(net "GND")
		)
		(pad "40" smd rect
			(at -2.050034 -30.174946 270)
			(size 0.519938 1.4986)
			(layers "F.Cu" "F.Mask" "F.Paste")
			(net "M_D_CPU1_SA_DQ<24>")
		)
		(pad "41" smd rect
			(at -2.050034 -29.325062 270)
			(size 0.519938 1.4986)
			(layers "F.Cu" "F.Mask" "F.Paste")
			(net "GND")
		)
		(pad "42" smd rect
			(at -2.050034 -28.474924 270)
			(size 0.519938 1.4986)
			(layers "F.Cu" "F.Mask" "F.Paste")
			(net "M_D_CPU1_SA_DQ<25>")
		)
		(pad "43" smd rect
			(at -2.050034 -27.62504 270)
			(size 0.519938 1.4986)
			(layers "F.Cu" "F.Mask" "F.Paste")
			(net "GND")
		)
		(pad "44" smd rect
			(at -2.050034 -26.774902 270)
			(size 0.519938 1.4986)
			(layers "F.Cu" "F.Mask" "F.Paste")
			(net "M_D_CPU1_SA_DQS_DP<3>")
		)
		(pad "45" smd rect
			(at -2.050034 -25.925018 270)
			(size 0.519938 1.4986)
			(layers "F.Cu" "F.Mask" "F.Paste")
			(net "M_D_CPU1_SA_DQS_DN<3>")
		)
	)
)
